(kicad_pcb
	(version 20260206)
	(generator "pcbnew")
	(generator_version "10.0")
	(general
		(thickness 1.6)
		(legacy_teardrops no)
	)
	(paper "A4")
	(title_block
		(title "Bryce Canyon_R.DPB_16317-1_OCP.brd")
		(comment 1 "Bryce Canyon / footprints 617-622 of 2099")
	)
	(layers
		(0 "F.Cu" signal "TOP")
		(4 "In1.Cu" signal "L2GND")
		(6 "In2.Cu" signal "L3")
		(8 "In3.Cu" signal "L4VCC")
		(10 "In4.Cu" signal "L5VCC")
		(12 "In5.Cu" signal "L6")
		(14 "In6.Cu" signal "L7GND")
		(2 "B.Cu" signal "BOTTOM")
		(9 "F.Adhes" user "F.Adhesive")
		(11 "B.Adhes" user "B.Adhesive")
		(13 "F.Paste" user "Package Geometry/Pastemask Top")
		(15 "B.Paste" user "Package Geometry/Pastemask Bottom")
		(5 "F.SilkS" user "Ref Des/Silkscreen Top")
		(7 "B.SilkS" user "Ref Des/Silkscreen Bottom")
		(1 "F.Mask" user "Board Geometry/Soldermask Top")
		(3 "B.Mask" user "Board Geometry/Soldermask Bottom")
		(17 "Dwgs.User" user "User.Drawings")
		(19 "Cmts.User" user "User.Comments")
		(21 "Eco1.User" user "User.Eco1")
		(23 "Eco2.User" user "User.Eco2")
		(25 "Edge.Cuts" user "Board Geometry/Outline")
		(27 "Margin" user)
		(31 "F.CrtYd" user "Package Geometry/Place Bound Top")
		(29 "B.CrtYd" user "Package Geometry/Place Bound Bottom")
		(35 "F.Fab" user "Ref Des/Assembly Top")
		(33 "B.Fab" user "Ref Des/Assembly Bottom")
	)
	(footprint ""
		(layer "F.Cu")
		(at 50.038 -19.939 -90)
		(property "Reference" "R652"
			(at 0 0 270)
			(layer "F.SilkS")
			(hide yes)
			(effects
				(font
					(size 1.27 1.27)
				)
			)
		)
		(property "Value" "4K7R2J-2-GP"
			(at 0.064008 -3.993896 270)
			(unlocked yes)
			(layer "F.Fab")
			(hide yes)
			(effects
				(font
					(size 1.016 1.016)
					(thickness 0.1524)
				)
			)
		)
		(property "Device Type" "R402H16"
			(at 0.064008 -5.517896 270)
			(unlocked yes)
			(layer "F.Fab")
			(hide yes)
			(effects
				(font
					(size 1.016 1.016)
					(thickness 0.1524)
				)
			)
		)
		(duplicate_pad_numbers_are_jumpers no)
		(fp_line
			(start -0.508 -0.9398)
			(end -0.508 0.9398)
			(stroke
				(width 0.1524)
				(type default)
			)
			(layer "F.SilkS")
		)
		(fp_line
			(start 0.508 -0.9398)
			(end -0.508 -0.9398)
			(stroke
				(width 0.1524)
				(type default)
			)
			(layer "F.SilkS")
		)
		(fp_rect
			(start -0.508 0.9398)
			(end 0.508 -0.9398)
			(stroke
				(width 0)
				(type default)
			)
			(fill no)
			(layer "F.CrtYd")
		)
		(fp_rect
			(start -0.508 0.9398)
			(end 0.508 -0.9398)
			(stroke
				(width 0)
				(type default)
			)
			(fill no)
			(layer "F.Fab")
		)
		(pad "1" smd custom
			(at 0 -0.4445 270)
			(size 0.1397 0.1397)
			(layers "F.Cu" "F.Mask" "F.Paste")
			(net "P12V_B")
			(options
				(clearance outline)
				(anchor circle)
			)
			(primitives
				(gr_poly
					(pts
						(arc
							(start -0.1778 -0.2794)
							(mid -0.249642 -0.249642)
							(end -0.2794 -0.1778)
						)
						(arc
							(start -0.2794 0.1778)
							(mid -0.249642 0.249642)
							(end -0.1778 0.2794)
						)
						(arc
							(start 0.1778 0.2794)
							(mid 0.249642 0.249642)
							(end 0.2794 0.1778)
						)
						(arc
							(start 0.2794 -0.1778)
							(mid 0.249642 -0.249642)
							(end 0.1778 -0.2794)
						)
					)
					(width 0)
					(fill yes)
				)
			)
		)
		(pad "2" smd custom
			(at 0 0.4445 270)
			(size 0.1397 0.1397)
			(layers "F.Cu" "F.Mask" "F.Paste")
			(net "SW_HDD_P25")
			(options
				(clearance outline)
				(anchor circle)
			)
			(primitives
				(gr_poly
					(pts
						(arc
							(start -0.1778 -0.2794)
							(mid -0.249642 -0.249642)
							(end -0.2794 -0.1778)
						)
						(arc
							(start -0.2794 0.1778)
							(mid -0.249642 0.249642)
							(end -0.1778 0.2794)
						)
						(arc
							(start 0.1778 0.2794)
							(mid 0.249642 0.249642)
							(end 0.2794 0.1778)
						)
						(arc
							(start 0.2794 -0.1778)
							(mid 0.249642 -0.249642)
							(end 0.1778 -0.2794)
						)
					)
					(width 0)
					(fill yes)
				)
			)
		)
	)
	(footprint ""
		(layer "F.Cu")
		(at 242.951 -228.219 -90)
		(property "Reference" "R83"
			(at 0 0 270)
			(layer "F.SilkS")
			(hide yes)
			(effects
				(font
					(size 1.27 1.27)
				)
			)
		)
		(property "Value" "4K7R2F-GP"
			(at 0.064008 -3.993896 270)
			(unlocked yes)
			(layer "F.Fab")
			(hide yes)
			(effects
				(font
					(size 1.016 1.016)
					(thickness 0.1524)
				)
			)
		)
		(property "Device Type" "R402H16"
			(at 0.064008 -5.517896 270)
			(unlocked yes)
			(layer "F.Fab")
			(hide yes)
			(effects
				(font
					(size 1.016 1.016)
					(thickness 0.1524)
				)
			)
		)
		(duplicate_pad_numbers_are_jumpers no)
		(fp_line
			(start -0.508 -0.9398)
			(end -0.508 0.9398)
			(stroke
				(width 0.1524)
				(type default)
			)
			(layer "F.SilkS")
		)
		(fp_line
			(start 0.508 -0.9398)
			(end -0.508 -0.9398)
			(stroke
				(width 0.1524)
				(type default)
			)
			(layer "F.SilkS")
		)
		(fp_rect
			(start -0.508 0.9398)
			(end 0.508 -0.9398)
			(stroke
				(width 0)
				(type default)
			)
			(fill no)
			(layer "F.CrtYd")
		)
		(fp_rect
			(start -0.508 0.9398)
			(end 0.508 -0.9398)
			(stroke
				(width 0)
				(type default)
			)
			(fill no)
			(layer "F.Fab")
		)
		(pad "1" smd custom
			(at 0 -0.4445 270)
			(size 0.1397 0.1397)
			(layers "F.Cu" "F.Mask" "F.Paste")
			(net "P3V3_STBY_B")
			(options
				(clearance outline)
				(anchor circle)
			)
			(primitives
				(gr_poly
					(pts
						(arc
							(start -0.1778 -0.2794)
							(mid -0.249642 -0.249642)
							(end -0.2794 -0.1778)
						)
						(arc
							(start -0.2794 0.1778)
							(mid -0.249642 0.249642)
							(end -0.1778 0.2794)
						)
						(arc
							(start 0.1778 0.2794)
							(mid 0.249642 0.249642)
							(end 0.2794 0.1778)
						)
						(arc
							(start 0.2794 -0.1778)
							(mid 0.249642 -0.249642)
							(end 0.1778 -0.2794)
						)
					)
					(width 0)
					(fill yes)
				)
			)
		)
		(pad "2" smd custom
			(at 0 0.4445 270)
			(size 0.1397 0.1397)
			(layers "F.Cu" "F.Mask" "F.Paste")
			(net "IO_EXP3_RESET#")
			(options
				(clearance outline)
				(anchor circle)
			)
			(primitives
				(gr_poly
					(pts
						(arc
							(start -0.1778 -0.2794)
							(mid -0.249642 -0.249642)
							(end -0.2794 -0.1778)
						)
						(arc
							(start -0.2794 0.1778)
							(mid -0.249642 0.249642)
							(end -0.1778 0.2794)
						)
						(arc
							(start 0.1778 0.2794)
							(mid 0.249642 0.249642)
							(end 0.2794 0.1778)
						)
						(arc
							(start 0.2794 -0.1778)
							(mid 0.249642 -0.249642)
							(end 0.1778 -0.2794)
						)
					)
					(width 0)
					(fill yes)
				)
			)
		)
	)
	(footprint ""
		(layer "F.Cu")
		(at 254.112522 -358.622346)
		(property "Reference" "C561"
			(at 0 0 0)
			(layer "F.SilkS")
			(hide yes)
			(effects
				(font
					(size 1.27 1.27)
				)
			)
		)
		(property "Value" "SCD1U25V2KX-2-GP"
			(at 1.1811 -2.7051 0)
			(unlocked yes)
			(layer "F.Fab")
			(hide yes)
			(effects
				(font
					(size 1.016 1.016)
					(thickness 0.1524)
				)
			)
		)
		(property "Device Type" "C402H22"
			(at 1.1811 -4.2291 0)
			(unlocked yes)
			(layer "F.Fab")
			(hide yes)
			(effects
				(font
					(size 1.016 1.016)
					(thickness 0.1524)
				)
			)
		)
		(duplicate_pad_numbers_are_jumpers no)
		(fp_rect
			(start -0.4318 0.9525)
			(end 0.4318 -0.9525)
			(stroke
				(width 0)
				(type default)
			)
			(fill no)
			(layer "F.CrtYd")
		)
		(fp_rect
			(start -0.4318 0.9525)
			(end 0.4318 -0.9525)
			(stroke
				(width 0)
				(type default)
			)
			(fill no)
			(layer "F.Fab")
		)
		(pad "1" smd custom
			(at 0 -0.4445)
			(size 0.1524 0.1524)
			(layers "F.Cu" "F.Mask" "F.Paste")
			(net "MB3_ISTART_R")
			(options
				(clearance outline)
				(anchor circle)
			)
			(primitives
				(gr_poly
					(pts
						(arc
							(start 0.3048 -0.2032)
							(mid 0.275042 -0.275042)
							(end 0.2032 -0.3048)
						)
						(arc
							(start -0.2032 -0.3048)
							(mid -0.275042 -0.275042)
							(end -0.3048 -0.2032)
						)
						(arc
							(start -0.3048 0.2032)
							(mid -0.275042 0.275042)
							(end -0.2032 0.3048)
						)
						(arc
							(start 0.2032 0.3048)
							(mid 0.275042 0.275042)
							(end 0.3048 0.2032)
						)
					)
					(width 0)
					(fill yes)
				)
			)
		)
		(pad "2" smd custom
			(at 0 0.4445)
			(size 0.1524 0.1524)
			(layers "F.Cu" "F.Mask" "F.Paste")
			(net "AGND_CURRENT_DPB")
			(options
				(clearance outline)
				(anchor circle)
			)
			(primitives
				(gr_poly
					(pts
						(arc
							(start 0.3048 -0.2032)
							(mid 0.275042 -0.275042)
							(end 0.2032 -0.3048)
						)
						(arc
							(start -0.2032 -0.3048)
							(mid -0.275042 -0.275042)
							(end -0.3048 -0.2032)
						)
						(arc
							(start -0.3048 0.2032)
							(mid -0.275042 0.275042)
							(end -0.2032 0.3048)
						)
						(arc
							(start 0.2032 0.3048)
							(mid 0.275042 0.275042)
							(end 0.3048 0.2032)
						)
					)
					(width 0)
					(fill yes)
				)
			)
		)
	)
	(footprint ""
		(layer "F.Cu")
		(at 406.554178 -99.756976 180)
		(property "Reference" "Q240"
			(at 0 0 180)
			(layer "F.SilkS")
			(hide yes)
			(effects
				(font
					(size 1.27 1.27)
				)
			)
		)
		(property "Value" "2N7002K-2-GP"
			(at 0.127 -8.9662 180)
			(unlocked yes)
			(layer "F.Fab")
			(hide yes)
			(effects
				(font
					(size 1.016 1.016)
					(thickness 0.1524)
				)
			)
		)
		(property "Device Type" "SOT23DGS2D4H44"
			(at 0.127 -10.4902 180)
			(unlocked yes)
			(layer "F.Fab")
			(hide yes)
			(effects
				(font
					(size 1.016 1.016)
					(thickness 0.1524)
				)
			)
		)
		(duplicate_pad_numbers_are_jumpers no)
		(fp_line
			(start 1.651 1.778)
			(end 1.651 -1.778)
			(stroke
				(width 0.1524)
				(type default)
			)
			(layer "F.SilkS")
		)
		(fp_line
			(start 1.651 -1.778)
			(end -1.651 -1.778)
			(stroke
				(width 0.1524)
				(type default)
			)
			(layer "F.SilkS")
		)
		(fp_line
			(start -1.651 1.778)
			(end 1.651 1.778)
			(stroke
				(width 0.1524)
				(type default)
			)
			(layer "F.SilkS")
		)
		(fp_line
			(start -1.651 -1.778)
			(end -1.651 1.778)
			(stroke
				(width 0.1524)
				(type default)
			)
			(layer "F.SilkS")
		)
		(fp_poly
			(pts
				(xy -1.778 1.8796) (xy -1.778 -1.8796) (xy 1.778 -1.8796) (xy 1.778 1.8796)
			)
			(stroke
				(width 0)
				(type default)
			)
			(fill no)
			(layer "F.CrtYd")
		)
		(fp_poly
			(pts
				(xy -1.778 1.8796) (xy -1.778 -1.8796) (xy 1.778 -1.8796) (xy 1.778 1.8796)
			)
			(stroke
				(width 0)
				(type default)
			)
			(fill no)
			(layer "F.Fab")
		)
		(pad "D" smd custom
			(at 0 -0.9525 180)
			(size 0.1905 0.1905)
			(layers "F.Cu" "F.Mask" "F.Paste")
			(net "FLT_HDD21_N")
			(options
				(clearance outline)
				(anchor circle)
			)
			(primitives
				(gr_poly
					(pts
						(arc
							(start -0.1778 0.5715)
							(mid -0.321484 0.511984)
							(end -0.381 0.3683)
						)
						(arc
							(start -0.381 -0.3683)
							(mid -0.321484 -0.511984)
							(end -0.1778 -0.5715)
						)
						(arc
							(start 0.1778 -0.5715)
							(mid 0.321484 -0.511984)
							(end 0.381 -0.3683)
						)
						(arc
							(start 0.381 0.3683)
							(mid 0.321484 0.511984)
							(end 0.1778 0.5715)
						)
					)
					(width 0)
					(fill yes)
				)
			)
		)
		(pad "G" smd custom
			(at -0.98425 0.9525 180)
			(size 0.1905 0.1905)
			(layers "F.Cu" "F.Mask" "F.Paste")
			(net "DRIVE_B_21_FLT_LED")
			(options
				(clearance outline)
				(anchor circle)
			)
			(primitives
				(gr_poly
					(pts
						(arc
							(start -0.1778 0.5715)
							(mid -0.321484 0.511984)
							(end -0.381 0.3683)
						)
						(arc
							(start -0.381 -0.3683)
							(mid -0.321484 -0.511984)
							(end -0.1778 -0.5715)
						)
						(arc
							(start 0.1778 -0.5715)
							(mid 0.321484 -0.511984)
							(end 0.381 -0.3683)
						)
						(arc
							(start 0.381 0.3683)
							(mid 0.321484 0.511984)
							(end 0.1778 0.5715)
						)
					)
					(width 0)
					(fill yes)
				)
			)
		)
		(pad "S" smd custom
			(at 0.98425 0.9525 180)
			(size 0.1905 0.1905)
			(layers "F.Cu" "F.Mask" "F.Paste")
			(net "GND")
			(options
				(clearance outline)
				(anchor circle)
			)
			(primitives
				(gr_poly
					(pts
						(arc
							(start -0.1778 0.5715)
							(mid -0.321484 0.511984)
							(end -0.381 0.3683)
						)
						(arc
							(start -0.381 -0.3683)
							(mid -0.321484 -0.511984)
							(end -0.1778 -0.5715)
						)
						(arc
							(start 0.1778 -0.5715)
							(mid 0.321484 -0.511984)
							(end 0.381 -0.3683)
						)
						(arc
							(start 0.381 0.3683)
							(mid 0.321484 0.511984)
							(end 0.1778 0.5715)
						)
					)
					(width 0)
					(fill yes)
				)
			)
		)
	)
	(footprint ""
		(layer "F.Cu")
		(at 207.3402 -196.088 90)
		(property "Reference" "R27"
			(at 0 0 90)
			(layer "F.SilkS")
			(hide yes)
			(effects
				(font
					(size 1.27 1.27)
				)
			)
		)
		(property "Value" "4K7R2F-GP"
			(at 0.064008 -3.993896 90)
			(unlocked yes)
			(layer "F.Fab")
			(hide yes)
			(effects
				(font
					(size 1.016 1.016)
					(thickness 0.1524)
				)
			)
		)
		(property "Device Type" "R402H16"
			(at 0.064008 -5.517896 90)
			(unlocked yes)
			(layer "F.Fab")
			(hide yes)
			(effects
				(font
					(size 1.016 1.016)
					(thickness 0.1524)
				)
			)
		)
		(duplicate_pad_numbers_are_jumpers no)
		(fp_line
			(start 0.508 -0.9398)
			(end -0.508 -0.9398)
			(stroke
				(width 0.1524)
				(type default)
			)
			(layer "F.SilkS")
		)
		(fp_line
			(start -0.508 -0.9398)
			(end -0.508 0.9398)
			(stroke
				(width 0.1524)
				(type default)
			)
			(layer "F.SilkS")
		)
		(fp_rect
			(start -0.508 0.9398)
			(end 0.508 -0.9398)
			(stroke
				(width 0)
				(type default)
			)
			(fill no)
			(layer "F.CrtYd")
		)
		(fp_rect
			(start -0.508 0.9398)
			(end 0.508 -0.9398)
			(stroke
				(width 0)
				(type default)
			)
			(fill no)
			(layer "F.Fab")
		)
		(pad "1" smd custom
			(at 0 -0.4445 90)
			(size 0.1397 0.1397)
			(layers "F.Cu" "F.Mask" "F.Paste")
			(net "P3V3_STBY_B")
			(options
				(clearance outline)
				(anchor circle)
			)
			(primitives
				(gr_poly
					(pts
						(arc
							(start -0.1778 -0.2794)
							(mid -0.249642 -0.249642)
							(end -0.2794 -0.1778)
						)
						(arc
							(start -0.2794 0.1778)
							(mid -0.249642 0.249642)
							(end -0.1778 0.2794)
						)
						(arc
							(start 0.1778 0.2794)
							(mid 0.249642 0.249642)
							(end 0.2794 0.1778)
						)
						(arc
							(start 0.2794 -0.1778)
							(mid 0.249642 -0.249642)
							(end 0.1778 -0.2794)
						)
					)
					(width 0)
					(fill yes)
				)
			)
		)
		(pad "2" smd custom
			(at 0 0.4445 90)
			(size 0.1397 0.1397)
			(layers "F.Cu" "F.Mask" "F.Paste")
			(net "IO_EXP2_HDD_FAULT_A2")
			(options
				(clearance outline)
				(anchor circle)
			)
			(primitives
				(gr_poly
					(pts
						(arc
							(start -0.1778 -0.2794)
							(mid -0.249642 -0.249642)
							(end -0.2794 -0.1778)
						)
						(arc
							(start -0.2794 0.1778)
							(mid -0.249642 0.249642)
							(end -0.1778 0.2794)
						)
						(arc
							(start 0.1778 0.2794)
							(mid 0.249642 0.249642)
							(end 0.2794 0.1778)
						)
						(arc
							(start 0.2794 -0.1778)
							(mid 0.249642 -0.249642)
							(end 0.1778 -0.2794)
						)
					)
					(width 0)
					(fill yes)
				)
			)
		)
	)
	(footprint ""
		(layer "F.Cu")
		(at 33.4264 -31.5976 180)
		(property "Reference" "R622"
			(at 0 0 180)
			(layer "F.SilkS")
			(hide yes)
			(effects
				(font
					(size 1.27 1.27)
				)
			)
		)
		(property "Value" "10KR2F-2-GP"
			(at 0.064008 -3.993896 180)
			(unlocked yes)
			(layer "F.Fab")
			(hide yes)
			(effects
				(font
					(size 1.016 1.016)
					(thickness 0.1524)
				)
			)
		)
		(property "Device Type" "R402H16"
			(at 0.064008 -5.517896 180)
			(unlocked yes)
			(layer "F.Fab")
			(hide yes)
			(effects
				(font
					(size 1.016 1.016)
					(thickness 0.1524)
				)
			)
		)
		(duplicate_pad_numbers_are_jumpers no)
		(fp_line
			(start 0.508 -0.9398)
			(end -0.508 -0.9398)
			(stroke
				(width 0.1524)
				(type default)
			)
			(layer "F.SilkS")
		)
		(fp_line
			(start -0.508 -0.9398)
			(end -0.508 0.9398)
			(stroke
				(width 0.1524)
				(type default)
			)
			(layer "F.SilkS")
		)
		(fp_rect
			(start -0.508 0.9398)
			(end 0.508 -0.9398)
			(stroke
				(width 0)
				(type default)
			)
			(fill no)
			(layer "F.CrtYd")
		)
		(fp_rect
			(start -0.508 0.9398)
			(end 0.508 -0.9398)
			(stroke
				(width 0)
				(type default)
			)
			(fill no)
			(layer "F.Fab")
		)
		(pad "1" smd custom
			(at 0 -0.4445 180)
			(size 0.1397 0.1397)
			(layers "F.Cu" "F.Mask" "F.Paste")
			(net "P3V3_STBY_B")
			(options
				(clearance outline)
				(anchor circle)
			)
			(primitives
				(gr_poly
					(pts
						(arc
							(start -0.1778 -0.2794)
							(mid -0.249642 -0.249642)
							(end -0.2794 -0.1778)
						)
						(arc
							(start -0.2794 0.1778)
							(mid -0.249642 0.249642)
							(end -0.1778 0.2794)
						)
						(arc
							(start 0.1778 0.2794)
							(mid 0.249642 0.249642)
							(end 0.2794 0.1778)
						)
						(arc
							(start 0.2794 -0.1778)
							(mid 0.249642 -0.249642)
							(end 0.1778 -0.2794)
						)
					)
					(width 0)
					(fill yes)
				)
			)
		)
		(pad "2" smd custom
			(at 0 0.4445 180)
			(size 0.1397 0.1397)
			(layers "F.Cu" "F.Mask" "F.Paste")
			(net "HDD_PRSNT_24")
			(options
				(clearance outline)
				(anchor circle)
			)
			(primitives
				(gr_poly
					(pts
						(arc
							(start -0.1778 -0.2794)
							(mid -0.249642 -0.249642)
							(end -0.2794 -0.1778)
						)
						(arc
							(start -0.2794 0.1778)
							(mid -0.249642 0.249642)
							(end -0.1778 0.2794)
						)
						(arc
							(start 0.1778 0.2794)
							(mid 0.249642 0.249642)
							(end 0.2794 0.1778)
						)
						(arc
							(start 0.2794 -0.1778)
							(mid 0.249642 -0.249642)
							(end 0.1778 -0.2794)
						)
					)
					(width 0)
					(fill yes)
				)
			)
		)
	)
)
